# BASEBOARD_FAB2 (Tioga Pass) — schematic netlist excerpt (pin names and nets, part order shuffled) for the footprints in the layout excerpt that follows; sources: Cadence DE-HDL packaged netlist, KiCad conversion of Wiwynn_Tioga_Pass_MB.brd

U9A1  TTL1G07_A  74LVC1G07 IC  pkg SOP  page 155 : A = SPA_5V_SIN_SW_D ; Y = SPA_SIN_SW_R
R6F6  RES  0.0 5% EMPTY  pkg 0402  page 104 : A = CLK_322M_156M_CPU0_OSC_VRM_DN ; B = CLK_156M_OSC_CPU0_HFI_DN
R7B10  RES  120.0 1% CHIP  pkg 0603  page 232 : A = PVPP_DEF ; B = GND

(kicad_pcb
	(version 20260206)
	(generator "pcbnew")
	(generator_version "10.0")
	(general
		(thickness 1.6)
		(legacy_teardrops no)
	)
	(paper "A4")
	(title_block
		(title "Wiwynn_Tioga_Pass_MB.brd")
		(comment 1 "Tioga Pass / footprints 10-12 of 4770")
	)
	(layers
		(0 "F.Cu" signal "TOP")
		(4 "In1.Cu" signal "L2GND")
		(6 "In2.Cu" signal "L3")
		(8 "In3.Cu" signal "L4GND")
		(10 "In4.Cu" signal "L5")
		(12 "In5.Cu" signal "L6GND")
		(14 "In6.Cu" signal "L7VCC")
		(16 "In7.Cu" signal "L8VCC")
		(18 "In8.Cu" signal "L9GND")
		(20 "In9.Cu" signal "L10")
		(22 "In10.Cu" signal "L11GND")
		(24 "In11.Cu" signal "L12")
		(26 "In12.Cu" signal "L13GND")
		(2 "B.Cu" signal "BOTTOM")
		(9 "F.Adhes" user "F.Adhesive")
		(11 "B.Adhes" user "B.Adhesive")
		(13 "F.Paste" user "Package Geometry/Pastemask Top")
		(15 "B.Paste" user "Package Geometry/Pastemask Bottom")
		(5 "F.SilkS" user "Ref Des/Silkscreen Top")
		(7 "B.SilkS" user "Ref Des/Silkscreen Bottom")
		(1 "F.Mask" user "Board Geometry/Soldermask Top")
		(3 "B.Mask" user "Board Geometry/Soldermask Bottom")
		(17 "Dwgs.User" user "User.Drawings")
		(19 "Cmts.User" user "User.Comments")
		(21 "Eco1.User" user "User.Eco1")
		(23 "Eco2.User" user "User.Eco2")
		(25 "Edge.Cuts" user "Board Geometry/Outline")
		(27 "Margin" user)
		(31 "F.CrtYd" user "Package Geometry/Place Bound Top")
		(29 "B.CrtYd" user "Package Geometry/Place Bound Bottom")
		(35 "F.Fab" user "Ref Des/Assembly Top")
		(33 "B.Fab" user "Ref Des/Assembly Bottom")
	)
	(footprint ""
		(layer "F.Cu")
		(at 335.292446 -129.480564)
		(property "Reference" "R7B10"
			(at 0 0 0)
			(layer "F.SilkS")
			(hide yes)
			(effects
				(font
					(size 1.27 1.27)
				)
			)
		)
		(property "Value" ""
			(at 0 0 0)
			(layer "F.Fab")
			(effects
				(font
					(size 1.27 1.27)
				)
			)
		)
		(duplicate_pad_numbers_are_jumpers no)
		(fp_poly
			(pts
				(xy -0.4953 -0.2032) (xy 0.4953 -0.2032) (xy 0.4953 1.6002) (xy -0.4953 1.6002)
			)
			(stroke
				(width 0)
				(type default)
			)
			(fill no)
			(layer "F.CrtYd")
		)
		(fp_line
			(start -0.4953 -0.2032)
			(end 0.4953 -0.2032)
			(stroke
				(width 0.1)
				(type default)
			)
			(layer "F.Fab")
		)
		(fp_line
			(start -0.4953 1.6002)
			(end -0.4953 -0.2032)
			(stroke
				(width 0.1)
				(type default)
			)
			(layer "F.Fab")
		)
		(fp_line
			(start 0.4953 -0.2032)
			(end 0.4953 1.6002)
			(stroke
				(width 0.1)
				(type default)
			)
			(layer "F.Fab")
		)
		(fp_line
			(start 0.4953 1.6002)
			(end -0.4953 1.6002)
			(stroke
				(width 0.1)
				(type default)
			)
			(layer "F.Fab")
		)
		(pad "1" smd rect
			(at 0 0)
			(size 0.762 0.889)
			(layers "F.Cu" "F.Mask" "F.Paste")
			(net "PVPP_DEF")
		)
		(pad "2" smd rect
			(at 0 1.397)
			(size 0.762 0.889)
			(layers "F.Cu" "F.Mask" "F.Paste")
			(net "GND")
		)
		(zone
			(layer "F.Cu")
			(hatch none 0.5)
			(connect_pads
				(clearance 0)
			)
			(min_thickness 0.25)
			(keepout
				(tracks not_allowed)
				(vias allowed)
				(pads allowed)
				(copperpour not_allowed)
				(footprints allowed)
			)
			(placement
				(enabled no)
				(sheetname "")
			)
			(fill
				(thermal_gap 0.5)
				(thermal_bridge_width 0.5)
				(island_removal_mode 0)
			)
			(polygon
				(pts
					(xy 334.911446 -128.528064) (xy 335.673446 -128.528064) (xy 335.673446 -129.036064) (xy 334.911446 -129.036064)
				)
			)
		)
		(zone
			(layer "F.Cu")
			(hatch none 0.5)
			(connect_pads
				(clearance 0)
			)
			(min_thickness 0.25)
			(keepout
				(tracks allowed)
				(vias not_allowed)
				(pads allowed)
				(copperpour not_allowed)
				(footprints allowed)
			)
			(placement
				(enabled no)
				(sheetname "")
			)
			(fill
				(thermal_gap 0.5)
				(thermal_bridge_width 0.5)
				(island_removal_mode 0)
			)
			(polygon
				(pts
					(xy 335.673446 -128.528064) (xy 335.673446 -129.036064) (xy 334.911446 -129.036064) (xy 334.911446 -128.528064)
				)
			)
		)
	)
	(footprint ""
		(layer "F.Cu")
		(at 490.453934 -148.717 -90)
		(property "Reference" "U9A1"
			(at -1.09855 1.85928 0)
			(unlocked yes)
			(layer "F.SilkS")
			(effects
				(font
					(size 0.7874 0.5842)
					(thickness 0.1524)
				)
				(justify left)
			)
		)
		(property "Value" ""
			(at 0 0 270)
			(layer "F.Fab")
			(effects
				(font
					(size 1.27 1.27)
				)
			)
		)
		(duplicate_pad_numbers_are_jumpers no)
		(fp_circle
			(center -0.4699 -0.8382)
			(end -0.4699 -0.9652)
			(stroke
				(width 0.254)
				(type default)
			)
			(fill no)
			(layer "F.SilkS")
		)
		(fp_poly
			(pts
				(xy 0.21463 -0.450088) (xy 1.56337 -0.450088) (xy 1.56337 1.75006) (xy 0.21463 1.75006)
			)
			(stroke
				(width 0)
				(type default)
			)
			(fill no)
			(layer "F.CrtYd")
		)
		(fp_line
			(start 0.21463 1.75006)
			(end 0.21463 -0.450088)
			(stroke
				(width 0.1)
				(type default)
			)
			(layer "F.Fab")
		)
		(fp_line
			(start 1.56337 1.75006)
			(end 0.21463 1.75006)
			(stroke
				(width 0.1)
				(type default)
			)
			(layer "F.Fab")
		)
		(fp_line
			(start 0.21463 -0.450088)
			(end 1.56337 -0.450088)
			(stroke
				(width 0.1)
				(type default)
			)
			(layer "F.Fab")
		)
		(fp_line
			(start 1.56337 -0.450088)
			(end 1.56337 1.75006)
			(stroke
				(width 0.1)
				(type default)
			)
			(layer "F.Fab")
		)
		(fp_circle
			(center -0.4699 -0.8382)
			(end -0.4699 -0.9652)
			(stroke
				(width 0.254)
				(type default)
			)
			(fill no)
			(layer "F.Fab")
		)
		(pad "1" smd rect
			(at 0 0 270)
			(size 1.016 0.381)
			(layers "F.Cu" "F.Mask" "F.Paste")
			(net "Net_6476")
		)
		(pad "2" smd rect
			(at 0 0.649986 270)
			(size 1.016 0.381)
			(layers "F.Cu" "F.Mask" "F.Paste")
			(net "SPA_5V_SIN_SW_D")
		)
		(pad "3" smd rect
			(at 0 1.299972 270)
			(size 1.016 0.381)
			(layers "F.Cu" "F.Mask" "F.Paste")
			(net "GND")
		)
		(pad "4" smd rect
			(at 1.778 1.299972 270)
			(size 1.016 0.381)
			(layers "F.Cu" "F.Mask" "F.Paste")
			(net "SPA_SIN_SW_R")
		)
		(pad "5" smd rect
			(at 1.778 0 270)
			(size 1.016 0.381)
			(layers "F.Cu" "F.Mask" "F.Paste")
			(net "P3V3_STBY")
		)
	)
	(footprint ""
		(layer "F.Cu")
		(at 318.8716 -30.585918)
		(property "Reference" "R6F6"
			(at 0 0 0)
			(layer "F.SilkS")
			(hide yes)
			(effects
				(font
					(size 1.27 1.27)
				)
			)
		)
		(property "Value" ""
			(at 0 0 0)
			(layer "F.Fab")
			(effects
				(font
					(size 1.27 1.27)
				)
			)
		)
		(duplicate_pad_numbers_are_jumpers no)
		(fp_poly
			(pts
				(xy -0.2794 -0.1016) (xy 0.2794 -0.1016) (xy 0.2794 0.9906) (xy -0.2794 0.9906)
			)
			(stroke
				(width 0)
				(type default)
			)
			(fill no)
			(layer "F.CrtYd")
		)
		(fp_line
			(start -0.2794 -0.1016)
			(end -0.2794 0.9906)
			(stroke
				(width 0.1)
				(type default)
			)
			(layer "F.Fab")
		)
		(fp_line
			(start -0.2794 0.9906)
			(end 0.2794 0.9906)
			(stroke
				(width 0.1)
				(type default)
			)
			(layer "F.Fab")
		)
		(fp_line
			(start 0.2794 -0.1016)
			(end -0.2794 -0.1016)
			(stroke
				(width 0.1)
				(type default)
			)
			(layer "F.Fab")
		)
		(fp_line
			(start 0.2794 0.9906)
			(end 0.2794 -0.1016)
			(stroke
				(width 0.1)
				(type default)
			)
			(layer "F.Fab")
		)
		(pad "1" smd rect
			(at 0 0)
			(size 0.508 0.508)
			(layers "F.Cu" "F.Mask" "F.Paste")
			(net "CLK_322M_156M_CPU0_OSC_VRM_DN")
		)
		(pad "2" smd rect
			(at 0 0.889)
			(size 0.508 0.508)
			(layers "F.Cu" "F.Mask" "F.Paste")
			(net "CLK_156M_OSC_CPU0_HFI_DN")
		)
		(zone
			(layer "F.Cu")
			(hatch none 0.5)
			(connect_pads
				(clearance 0)
			)
			(min_thickness 0.25)
			(keepout
				(tracks allowed)
				(vias not_allowed)
				(pads allowed)
				(copperpour not_allowed)
				(footprints allowed)
			)
			(placement
				(enabled no)
				(sheetname "")
			)
			(fill
				(thermal_gap 0.5)
				(thermal_bridge_width 0.5)
				(island_removal_mode 0)
			)
			(polygon
				(pts
					(xy 318.6176 -30.331918) (xy 319.1256 -30.331918) (xy 319.1256 -29.950918) (xy 318.6176 -29.950918)
				)
			)
		)
		(zone
			(layer "F.Cu")
			(hatch none 0.5)
			(connect_pads
				(clearance 0)
			)
			(min_thickness 0.25)
			(keepout
				(tracks not_allowed)
				(vias allowed)
				(pads allowed)
				(copperpour not_allowed)
				(footprints allowed)
			)
			(placement
				(enabled no)
				(sheetname "")
			)
			(fill
				(thermal_gap 0.5)
				(thermal_bridge_width 0.5)
				(island_removal_mode 0)
			)
			(polygon
				(pts
					(xy 318.6176 -29.950918) (xy 319.1256 -29.950918) (xy 319.1256 -30.331918) (xy 318.6176 -30.331918)
				)
			)
		)
	)
)
